# S9S_MB_2U (Grand Teton) — schematic netlist excerpt (pin names and nets, part order shuffled) for the footprints in the layout excerpt that follows; sources: Cadence DE-HDL packaged netlist, KiCad conversion of 03242023_DA0F0TMBIJ0_F0T_Motherboard_J_brd_V01_OCP.brd

J13  SCONN288_ADR50017P130CC  SCONN288_ADR50017-P130CC IO  pkg DDR288S_1-1VXB  page 94
  VIN_BULK0  = P12V_S3_AUX_CPU0_NVDIMM
  RFU0  = TP_CHG_CPU0_DIMM1_FRU_0
  VIN_MGMT  = P3V3_AUX
  HSCL  = I3C_SPD_DDREFGH_CPU0_LVC1_SCL_4
  HSDA  = I3C_SPD_DDREFGH_CPU0_LVC1_SDA
  VSS0  = GND
  DQ0_A  = M_G_CPU0_SA_DQ<0>
  VSS1  = GND
  DQ1_A  = M_G_CPU0_SA_DQ<1>
  VSS2  = GND
  DQS0_A_T  = M_G_CPU0_SA_DQS_DP<0>
  DQS0_A_C  = M_G_CPU0_SA_DQS_DN<0>
  VSS3  = GND
  DQ4_A  = M_G_CPU0_SA_DQ<4>
  VSS4  = GND
  DQ5_A  = M_G_CPU0_SA_DQ<5>
  VSS5  = GND
  DQ8_A  = M_G_CPU0_SA_DQ<8>
  VSS6  = GND
  DQ9_A  = M_G_CPU0_SA_DQ<9>
  VSS7  = GND
  DQS1_A_T  = M_G_CPU0_SA_DQS_DP<1>
  DQS1_A_C  = M_G_CPU0_SA_DQS_DN<1>
  VSS8  = GND
  DQ12_A  = M_G_CPU0_SA_DQ<12>
  VSS9  = GND
  DQ13_A  = M_G_CPU0_SA_DQ<13>
  VSS10  = GND
  DQ16_A  = M_G_CPU0_SA_DQ<16>
  VSS11  = GND
  DQ17_A  = M_G_CPU0_SA_DQ<17>
  VSS12  = GND
  DQS2_A_T  = M_G_CPU0_SA_DQS_DP<2>
  DQS2_A_C  = M_G_CPU0_SA_DQS_DN<2>
  VSS13  = GND
  DQ20_A  = M_G_CPU0_SA_DQ<20>
  VSS14  = GND
  DQ21_A  = M_G_CPU0_SA_DQ<21>
  VSS15  = GND
  DQ24_A  = M_G_CPU0_SA_DQ<24>
  VSS16  = GND
  DQ25_A  = M_G_CPU0_SA_DQ<25>
  VSS17  = GND
  DQS3_A_T  = M_G_CPU0_SA_DQS_DP<3>
  DQS3_A_C  = M_G_CPU0_SA_DQS_DN<3>
  VSS18  = GND
  DQ28_A  = M_G_CPU0_SA_DQ<28>
  VSS19  = GND
  DQ29_A  = M_G_CPU0_SA_DQ<29>
  VSS20  = GND
  CB0_A  = M_G_CPU0_SA_CB<0>
  VSS21  = GND
  CB1_A  = M_G_CPU0_SA_CB<1>
  VSS22  = GND
  DQS4_A_T  = M_G_CPU0_SA_DQS_DP<4>
  DQS4_A_C  = M_G_CPU0_SA_DQS_DN<4>
  VSS23  = GND
  CB4_A  = M_G_CPU0_SA_CB<4>
  VSS24  = GND
  CB5_A  = M_G_CPU0_SA_CB<5>
  VSS25  = GND
  ALERT_N  = M_G_CPU0_ALERT_N
  VSS26  = GND
  CS0_A_N  = M_G_CPU0_SA_CS_N<0>
  VSS27  = GND
  CA0_A  = M_G_CPU0_SA_CA<0>
  VSS28  = GND
  CA2_A  = M_G_CPU0_SA_CA<2>
  VSS29  = GND
  CA4_A  = M_G_CPU0_SA_CA<4>
  VSS30  = GND
  CA6_A  = M_G_CPU0_SA_CA<6>
  VSS31  = GND
  PAR_A  = M_G_CPU0_SA_PAR
  VSS32  = GND
  CA0_B  = M_G_CPU0_SB_CA<0>
  VSS33  = GND
  CA2_B  = M_G_CPU0_SB_CA<2>
  VSS34  = GND
  CA4_B  = M_G_CPU0_SB_CA<4>
  VSS35  = GND
  CA6_B  = M_G_CPU0_SB_CA<6>
  VSS36  = GND
  CS0_B_N  = M_G_CPU0_SB_CS_N<0>
  VSS37  = GND
  \lbd||rsp_a_n\  = M_G_CPU0_SA_RSP<0>
  \lbs||rsp_b_n\  = M_G_CPU0_SB_RSP<0>
  VSS38  = GND
  CB4_B  = M_G_CPU0_SB_CB<4>
  VSS39  = GND
  CB5_B  = M_G_CPU0_SB_CB<5>
  VSS40  = GND
  \dqs9_b_t||tdqs9_b_t||dbi4_b_n\  = M_G_CPU0_SB_DQS_DP<9>
  \dqs9_b_c||tdqs9_b_c\  = M_G_CPU0_SB_DQS_DN<9>
  VSS41  = GND
  CB0_B  = M_G_CPU0_SB_CB<0>
  VSS42  = GND
  CB1_B  = M_G_CPU0_SB_CB<1>
  VSS43  = GND
  DQ0_B  = M_G_CPU0_SB_DQ<0>
  VSS44  = GND
  DQ1_B  = M_G_CPU0_SB_DQ<1>
  VSS45  = GND
  DQS0_B_T  = M_G_CPU0_SB_DQS_DP<0>
  DQS0_B_C  = M_G_CPU0_SB_DQS_DN<0>
  VSS46  = GND
  DQ4_B  = M_G_CPU0_SB_DQ<4>
  VSS47  = GND
  DQ5_B  = M_G_CPU0_SB_DQ<5>
  VSS48  = GND
  DQ8_B  = M_G_CPU0_SB_DQ<8>
  VSS49  = GND
  DQ9_B  = M_G_CPU0_SB_DQ<9>
  VSS50  = GND
  DQS1_B_T  = M_G_CPU0_SB_DQS_DP<1>
  DQS1_B_C  = M_G_CPU0_SB_DQS_DN<1>
  VSS51  = GND
  DQ12_B  = M_G_CPU0_SB_DQ<12>
  VSS52  = GND
  DQ13_B  = M_G_CPU0_SB_DQ<13>
  VSS53  = GND
  DQ16_B  = M_G_CPU0_SB_DQ<16>
  VSS54  = GND
  DQ17_B  = M_G_CPU0_SB_DQ<17>
  VSS55  = GND
  DQS2_B_T  = M_G_CPU0_SB_DQS_DP<2>
  DQS2_B_C  = M_G_CPU0_SB_DQS_DN<2>
  VSS56  = GND
  DQ20_B  = M_G_CPU0_SB_DQ<20>
  VSS57  = GND
  DQ21_B  = M_G_CPU0_SB_DQ<21>
  VSS58  = GND
  DQ24_B  = M_G_CPU0_SB_DQ<24>
  VSS59  = GND
  DQ25_B  = M_G_CPU0_SB_DQ<25>
  VSS60  = GND
  DQS3_B_T  = M_G_CPU0_SB_DQS_DP<3>
  DQS3_B_C  = M_G_CPU0_SB_DQS_DN<3>
  VSS61  = GND
  DQ28_B  = M_G_CPU0_SB_DQ<28>
  VSS62  = GND
  DQ29_B  = M_G_CPU0_SB_DQ<29>
  VSS63  = GND
  RFU1  = TP_CHG_CPU0_DIMM1_FRU_1
  VIN_BULK1  = P12V_S3_AUX_CPU0_NVDIMM
  VIN_BULK2  = P12V_S3_AUX_CPU0_NVDIMM
  \pwr_good||fail_n\  = PWRGD_CHG_CPU0_DIMM1
  HSA  = PD_CHG_CPU0_DIMM1_SAA
  RFU2  = TP_CHG_CPU0_DIMM1_FRU_2
  RFU3  = TP_CHG_CPU0_DIMM1_FRU_3
  VSS64  = GND
  DQ2_A  = M_G_CPU0_SA_DQ<2>
  VSS65  = GND
  DQ3_A  = M_G_CPU0_SA_DQ<3>
  VSS66  = GND
  \dqs5_a_c||tdqs5_a_c||dqs5_a_t||tdqs5_a_t\  = M_G_CPU0_SA_DQS_DN<5>
  \dqs5_a_t||tdqs5_a_t\  = M_G_CPU0_SA_DQS_DP<5>
  VSS67  = GND
  DQ6_A  = M_G_CPU0_SA_DQ<6>
  VSS68  = GND
  DQ7_A  = M_G_CPU0_SA_DQ<7>
  VSS69  = GND
  DQ10_A  = M_G_CPU0_SA_DQ<10>
  VSS70  = GND
  DQ11_A  = M_G_CPU0_SA_DQ<11>
  VSS71  = GND
  \dqs6_a_c||tdqs6_a_c||dqs6_a_t||tdqs6_a_t\  = M_G_CPU0_SA_DQS_DN<6>
  \dqs6_a_t||tdqs6_a_t\  = M_G_CPU0_SA_DQS_DP<6>
  VSS72  = GND
  DQ14_A  = M_G_CPU0_SA_DQ<14>
  VSS73  = GND
  DQ15_A  = M_G_CPU0_SA_DQ<15>
  VSS74  = GND
  DQ18_A  = M_G_CPU0_SA_DQ<18>
  VSS75  = GND
  DQ19_A  = M_G_CPU0_SA_DQ<19>
  VSS76  = GND
  \dqs7_a_c||tdqs7_a_c\  = M_G_CPU0_SA_DQS_DN<7>
  \dqs7_a_t||tdqs7_a_t\  = M_G_CPU0_SA_DQS_DP<7>
  VSS77  = GND
  DQ22_A  = M_G_CPU0_SA_DQ<22>
  VSS78  = GND
  DQ23_A  = M_G_CPU0_SA_DQ<23>
  VSS79  = GND
  DQ26_A  = M_G_CPU0_SA_DQ<26>
  VSS80  = GND
  DQ27_A  = M_G_CPU0_SA_DQ<27>
  VSS81  = GND
  \dqs8_a_c||tdqs8_a_c\  = M_G_CPU0_SA_DQS_DN<8>
  \dqs8_a_t||tdqs8_a_t\  = M_G_CPU0_SA_DQS_DP<8>
  VSS82  = GND
  DQ30_A  = M_G_CPU0_SA_DQ<30>
  VSS83  = GND
  DQ31_A  = M_G_CPU0_SA_DQ<31>
  VSS84  = GND
  CB2_A  = M_G_CPU0_SA_CB<2>
  VSS85  = GND
  CB3_A  = M_G_CPU0_SA_CB<3>
  VSS86  = GND
  \dqs9_a_c||tdqs9_a_c\  = M_G_CPU0_SA_DQS_DN<9>
  \dqs9_a_t||tdqs9_a_t\  = M_G_CPU0_SA_DQS_DP<9>
  VSS87  = GND
  CB6_A  = M_G_CPU0_SA_CB<6>
  VSS88  = GND
  CB7_A  = M_G_CPU0_SA_CB<7>
  VSS89  = GND
  RESET_N  = RST_M_GH_CPU0_FPGA_N
  VSS90  = GND
  CS1_A_N  = M_G_CPU0_SA_CS_N<1>
  VSS91  = GND
  CA1_A  = M_G_CPU0_SA_CA<1>
  VSS92  = GND
  CA3_A  = M_G_CPU0_SA_CA<3>
  VSS93  = GND
  CA5_A  = M_G_CPU0_SA_CA<5>
  VSS94  = GND
  CK_T  = M_G_CPU0_CLK_DP<0>
  CK_C  = M_G_CPU0_CLK_DN<0>
  VSS95  = GND
  RFU4  = TP_CHG_CPU0_DIMM1_FRU_4
  CA1_B  = M_G_CPU0_SB_CA<1>
  VSS96  = GND
  CA3_B  = M_G_CPU0_SB_CA<3>
  VSS97  = GND
  CA5_B  = M_G_CPU0_SB_CA<5>
  VSS98  = GND
  PAR_B  = M_G_CPU0_SB_PAR
  VSS99  = GND
  CS1_B_N  = M_G_CPU0_SB_CS_N<1>
  VSS100  = GND
  RFU5  = TP_CHG_CPU0_DIMM1_FRU_5
  RFU6  = TP_CHG_CPU0_DIMM1_FRU_6
  VSS101  = GND
  CB6_B  = M_G_CPU0_SB_CB<6>
  VSS102  = GND
  CB7_B  = M_G_CPU0_SB_CB<7>
  VSS103  = GND
  DQS4_B_C  = M_G_CPU0_SB_DQS_DN<4>
  DQS4_B_T  = M_G_CPU0_SB_DQS_DP<4>
  VSS104  = GND
  CB2_B  = M_G_CPU0_SB_CB<2>
  VSS105  = GND
  CB3_B  = M_G_CPU0_SB_CB<3>
  VSS106  = GND
  DQ2_B  = M_G_CPU0_SB_DQ<2>
  VSS107  = GND
  DQ3_B  = M_G_CPU0_SB_DQ<3>
  VSS108  = GND
  \dqs5_b_c||tdqs5_b_c\  = M_G_CPU0_SB_DQS_DN<5>
  \dqs5_b_t||tdqs5_b_t\  = M_G_CPU0_SB_DQS_DP<5>
  VSS109  = GND
  DQ6_B  = M_G_CPU0_SB_DQ<6>
  VSS110  = GND
  DQ7_B  = M_G_CPU0_SB_DQ<7>
  VSS111  = GND
  DQ10_B  = M_G_CPU0_SB_DQ<10>
  VSS112  = GND
  DQ11_B  = M_G_CPU0_SB_DQ<11>
  VSS113  = GND
  \dqs6_b_c||tdqs6_b_c\  = M_G_CPU0_SB_DQS_DN<6>
  \dqs6_b_t||tdqs6_b_t\  = M_G_CPU0_SB_DQS_DP<6>
  VSS114  = GND
  DQ14_B  = M_G_CPU0_SB_DQ<14>
  VSS115  = GND
  DQ15_B  = M_G_CPU0_SB_DQ<15>
  VSS116  = GND
  DQ18_B  = M_G_CPU0_SB_DQ<18>
  VSS117  = GND
  DQ19_B  = M_G_CPU0_SB_DQ<19>
  VSS118  = GND
  \dqs7_b_c||tdqs7_b_c\  = M_G_CPU0_SB_DQS_DN<7>
  \dqs7_b_t||tdqs7_b_t\  = M_G_CPU0_SB_DQS_DP<7>
  VSS119  = GND
  DQ22_B  = M_G_CPU0_SB_DQ<22>
  VSS120  = GND
  DQ23_B  = M_G_CPU0_SB_DQ<23>
  VSS121  = GND
  DQ26_B  = M_G_CPU0_SB_DQ<26>
  VSS122  = GND
  DQ27_B  = M_G_CPU0_SB_DQ<27>
  VSS123  = GND
  \dqs8_b_c||tdqs8_b_c\  = M_G_CPU0_SB_DQS_DN<8>
  \dqs8_b_t||tdqs8_b_t\  = M_G_CPU0_SB_DQS_DP<8>
  VSS124  = GND
  DQ30_B  = M_G_CPU0_SB_DQ<30>
  VSS125  = GND
  DQ31_B  = M_G_CPU0_SB_DQ<31>
  VSS126  = GND
  G1  = GND
  G2  = GND
  G3  = GND

(kicad_pcb
	(version 20260206)
	(generator "pcbnew")
	(generator_version "10.0")
	(general
		(thickness 1.6)
		(legacy_teardrops no)
	)
	(paper "A4")
	(title_block
		(title "03242023_DA0F0TMBIJ0_F0T_Motherboard_J_brd_V01_OCP.brd")
		(comment 1 "Grand Teton / footprint 1368 of 6105 (J13), pads 183-228 of 291")
	)
	(layers
		(0 "F.Cu" signal "TOP")
		(4 "In1.Cu" signal "GND")
		(6 "In2.Cu" signal "IN1")
		(8 "In3.Cu" signal "GND1")
		(10 "In4.Cu" signal "IN2")
		(12 "In5.Cu" signal "GND2")
		(14 "In6.Cu" signal "IN3")
		(16 "In7.Cu" signal "GND3")
		(18 "In8.Cu" signal "VCC")
		(20 "In9.Cu" signal "VCC1")
		(22 "In10.Cu" signal "GND4")
		(24 "In11.Cu" signal "IN4")
		(26 "In12.Cu" signal "GND5")
		(28 "In13.Cu" signal "IN5")
		(30 "In14.Cu" signal "GND6")
		(32 "In15.Cu" signal "IN6")
		(34 "In16.Cu" signal "GND7")
		(2 "B.Cu" signal "BOTTOM")
		(9 "F.Adhes" user "F.Adhesive")
		(11 "B.Adhes" user "B.Adhesive")
		(13 "F.Paste" user "Package Geometry/Pastemask Top")
		(15 "B.Paste" user "Package Geometry/Pastemask Bottom")
		(5 "F.SilkS" user "Ref Des/Silkscreen Top")
		(7 "B.SilkS" user "Ref Des/Silkscreen Bottom")
		(1 "F.Mask" user "Board Geometry/Soldermask Top")
		(3 "B.Mask" user "Board Geometry/Soldermask Bottom")
		(17 "Dwgs.User" user "User.Drawings")
		(19 "Cmts.User" user "User.Comments")
		(21 "Eco1.User" user "User.Eco1")
		(23 "Eco2.User" user "User.Eco2")
		(25 "Edge.Cuts" user "Board Geometry/Outline")
		(27 "Margin" user)
		(31 "F.CrtYd" user "Package Geometry/Place Bound Top")
		(29 "B.CrtYd" user "Package Geometry/Place Bound Bottom")
		(35 "F.Fab" user "Ref Des/Assembly Top")
		(33 "B.Fab" user "Ref Des/Assembly Bottom")
	)
	(footprint ""
		(layer "F.Cu")
		(at 446.522348 -258.091686)
		(property "Reference" "J13"
			(at -3.683 -81.702148 0)
			(unlocked yes)
			(layer "F.SilkS")
			(effects
				(font
					(size 0.7874 0.5842)
					(thickness 0.1524)
				)
				(justify left)
			)
		)
		(property "Value" ""
			(at 0 0 0)
			(layer "F.Fab")
			(effects
				(font
					(size 1.27 1.27)
				)
			)
		)
		(duplicate_pad_numbers_are_jumpers no)
		(pad "183" smd rect
			(at 2.050034 -31.025084 270)
			(size 0.519938 1.4986)
			(layers "F.Cu" "F.Mask" "F.Paste")
			(net "M_G_CPU0_SA_DQ<23>")
		)
		(pad "184" smd rect
			(at 2.050034 -30.174946 270)
			(size 0.519938 1.4986)
			(layers "F.Cu" "F.Mask" "F.Paste")
			(net "GND")
		)
		(pad "185" smd rect
			(at 2.050034 -29.325062 270)
			(size 0.519938 1.4986)
			(layers "F.Cu" "F.Mask" "F.Paste")
			(net "M_G_CPU0_SA_DQ<26>")
		)
		(pad "186" smd rect
			(at 2.050034 -28.474924 270)
			(size 0.519938 1.4986)
			(layers "F.Cu" "F.Mask" "F.Paste")
			(net "GND")
		)
		(pad "187" smd rect
			(at 2.050034 -27.62504 270)
			(size 0.519938 1.4986)
			(layers "F.Cu" "F.Mask" "F.Paste")
			(net "M_G_CPU0_SA_DQ<27>")
		)
		(pad "188" smd rect
			(at 2.050034 -26.774902 270)
			(size 0.519938 1.4986)
			(layers "F.Cu" "F.Mask" "F.Paste")
			(net "GND")
		)
		(pad "189" smd rect
			(at 2.050034 -25.925018 270)
			(size 0.519938 1.4986)
			(layers "F.Cu" "F.Mask" "F.Paste")
			(net "M_G_CPU0_SA_DQS_DN<8>")
		)
		(pad "190" smd rect
			(at 2.050034 -25.07488 270)
			(size 0.519938 1.4986)
			(layers "F.Cu" "F.Mask" "F.Paste")
			(net "M_G_CPU0_SA_DQS_DP<8>")
		)
		(pad "191" smd rect
			(at 2.050034 -24.224996 270)
			(size 0.519938 1.4986)
			(layers "F.Cu" "F.Mask" "F.Paste")
			(net "GND")
		)
		(pad "192" smd rect
			(at 2.050034 -23.375112 270)
			(size 0.519938 1.4986)
			(layers "F.Cu" "F.Mask" "F.Paste")
			(net "M_G_CPU0_SA_DQ<30>")
		)
		(pad "193" smd rect
			(at 2.050034 -22.524974 270)
			(size 0.519938 1.4986)
			(layers "F.Cu" "F.Mask" "F.Paste")
			(net "GND")
		)
		(pad "194" smd rect
			(at 2.050034 -21.67509 270)
			(size 0.519938 1.4986)
			(layers "F.Cu" "F.Mask" "F.Paste")
			(net "M_G_CPU0_SA_DQ<31>")
		)
		(pad "195" smd rect
			(at 2.050034 -20.824952 270)
			(size 0.519938 1.4986)
			(layers "F.Cu" "F.Mask" "F.Paste")
			(net "GND")
		)
		(pad "196" smd rect
			(at 2.050034 -19.975068 270)
			(size 0.519938 1.4986)
			(layers "F.Cu" "F.Mask" "F.Paste")
			(net "M_G_CPU0_SA_CB<2>")
		)
		(pad "197" smd rect
			(at 2.050034 -19.12493 270)
			(size 0.519938 1.4986)
			(layers "F.Cu" "F.Mask" "F.Paste")
			(net "GND")
		)
		(pad "198" smd rect
			(at 2.050034 -18.275046 270)
			(size 0.519938 1.4986)
			(layers "F.Cu" "F.Mask" "F.Paste")
			(net "M_G_CPU0_SA_CB<3>")
		)
		(pad "199" smd rect
			(at 2.050034 -17.424908 270)
			(size 0.519938 1.4986)
			(layers "F.Cu" "F.Mask" "F.Paste")
			(net "GND")
		)
		(pad "200" smd rect
			(at 2.050034 -16.575024 270)
			(size 0.519938 1.4986)
			(layers "F.Cu" "F.Mask" "F.Paste")
			(net "M_G_CPU0_SA_DQS_DN<9>")
		)
		(pad "201" smd rect
			(at 2.050034 -15.724886 270)
			(size 0.519938 1.4986)
			(layers "F.Cu" "F.Mask" "F.Paste")
			(net "M_G_CPU0_SA_DQS_DP<9>")
		)
		(pad "202" smd rect
			(at 2.050034 -14.875002 270)
			(size 0.519938 1.4986)
			(layers "F.Cu" "F.Mask" "F.Paste")
			(net "GND")
		)
		(pad "203" smd rect
			(at 2.050034 -14.025118 270)
			(size 0.519938 1.4986)
			(layers "F.Cu" "F.Mask" "F.Paste")
			(net "M_G_CPU0_SA_CB<6>")
		)
		(pad "204" smd rect
			(at 2.050034 -13.17498 270)
			(size 0.519938 1.4986)
			(layers "F.Cu" "F.Mask" "F.Paste")
			(net "GND")
		)
		(pad "205" smd rect
			(at 2.050034 -12.325096 270)
			(size 0.519938 1.4986)
			(layers "F.Cu" "F.Mask" "F.Paste")
			(net "M_G_CPU0_SA_CB<7>")
		)
		(pad "206" smd rect
			(at 2.050034 -11.474958 270)
			(size 0.519938 1.4986)
			(layers "F.Cu" "F.Mask" "F.Paste")
			(net "GND")
		)
		(pad "207" smd rect
			(at 2.050034 -10.625074 270)
			(size 0.519938 1.4986)
			(layers "F.Cu" "F.Mask" "F.Paste")
			(net "RST_M_GH_CPU0_FPGA_N")
		)
		(pad "208" smd rect
			(at 2.050034 -9.774936 270)
			(size 0.519938 1.4986)
			(layers "F.Cu" "F.Mask" "F.Paste")
			(net "GND")
		)
		(pad "209" smd rect
			(at 2.050034 -8.925052 270)
			(size 0.519938 1.4986)
			(layers "F.Cu" "F.Mask" "F.Paste")
			(net "M_G_CPU0_SA_CS_N<1>")
		)
		(pad "210" smd rect
			(at 2.050034 -8.074914 270)
			(size 0.519938 1.4986)
			(layers "F.Cu" "F.Mask" "F.Paste")
			(net "GND")
		)
		(pad "211" smd rect
			(at 2.050034 -7.22503 270)
			(size 0.519938 1.4986)
			(layers "F.Cu" "F.Mask" "F.Paste")
			(net "M_G_CPU0_SA_CA<1>")
		)
		(pad "212" smd rect
			(at 2.050034 -6.374892 270)
			(size 0.519938 1.4986)
			(layers "F.Cu" "F.Mask" "F.Paste")
			(net "GND")
		)
		(pad "213" smd rect
			(at 2.050034 -5.525008 270)
			(size 0.519938 1.4986)
			(layers "F.Cu" "F.Mask" "F.Paste")
			(net "M_G_CPU0_SA_CA<3>")
		)
		(pad "214" smd rect
			(at 2.050034 -4.675124 270)
			(size 0.519938 1.4986)
			(layers "F.Cu" "F.Mask" "F.Paste")
			(net "GND")
		)
		(pad "215" smd rect
			(at 2.050034 -3.824986 270)
			(size 0.519938 1.4986)
			(layers "F.Cu" "F.Mask" "F.Paste")
			(net "M_G_CPU0_SA_CA<5>")
		)
		(pad "216" smd rect
			(at 2.050034 -2.975102 270)
			(size 0.519938 1.4986)
			(layers "F.Cu" "F.Mask" "F.Paste")
			(net "GND")
		)
		(pad "217" smd rect
			(at 2.050034 -2.124964 270)
			(size 0.519938 1.4986)
			(layers "F.Cu" "F.Mask" "F.Paste")
			(net "M_G_CPU0_CLK_DP<0>")
		)
		(pad "218" smd rect
			(at 2.050034 -1.27508 270)
			(size 0.519938 1.4986)
			(layers "F.Cu" "F.Mask" "F.Paste")
			(net "M_G_CPU0_CLK_DN<0>")
		)
		(pad "219" smd rect
			(at 2.050034 -0.424942 270)
			(size 0.519938 1.4986)
			(layers "F.Cu" "F.Mask" "F.Paste")
			(net "GND")
		)
		(pad "220" smd rect
			(at 2.050034 5.525008 270)
			(size 0.519938 1.4986)
			(layers "F.Cu" "F.Mask" "F.Paste")
			(net "TP_CHG_CPU0_DIMM1_FRU_4")
		)
		(pad "221" smd rect
			(at 2.050034 6.374892 270)
			(size 0.519938 1.4986)
			(layers "F.Cu" "F.Mask" "F.Paste")
			(net "M_G_CPU0_SB_CA<1>")
		)
		(pad "222" smd rect
			(at 2.050034 7.22503 270)
			(size 0.519938 1.4986)
			(layers "F.Cu" "F.Mask" "F.Paste")
			(net "GND")
		)
		(pad "223" smd rect
			(at 2.050034 8.074914 270)
			(size 0.519938 1.4986)
			(layers "F.Cu" "F.Mask" "F.Paste")
			(net "M_G_CPU0_SB_CA<3>")
		)
		(pad "224" smd rect
			(at 2.050034 8.925052 270)
			(size 0.519938 1.4986)
			(layers "F.Cu" "F.Mask" "F.Paste")
			(net "GND")
		)
		(pad "225" smd rect
			(at 2.050034 9.774936 270)
			(size 0.519938 1.4986)
			(layers "F.Cu" "F.Mask" "F.Paste")
			(net "M_G_CPU0_SB_CA<5>")
		)
		(pad "226" smd rect
			(at 2.050034 10.625074 270)
			(size 0.519938 1.4986)
			(layers "F.Cu" "F.Mask" "F.Paste")
			(net "GND")
		)
		(pad "227" smd rect
			(at 2.050034 11.474958 270)
			(size 0.519938 1.4986)
			(layers "F.Cu" "F.Mask" "F.Paste")
			(net "M_G_CPU0_SB_PAR")
		)
		(pad "228" smd rect
			(at 2.050034 12.325096 270)
			(size 0.519938 1.4986)
			(layers "F.Cu" "F.Mask" "F.Paste")
			(net "GND")
		)
	)
)
